(kicad_pcb
	(version 20260206)
	(generator "pcbnew")
	(generator_version "10.0")
	(general
		(thickness 1.6)
		(legacy_teardrops no)
	)
	(paper "A4")
	(title_block
		(title "Bryce Canyon_SCC_16316-1_OCP.brd")
		(comment 1 "Bryce Canyon / footprints 1088-1096 of 1561")
	)
	(layers
		(0 "F.Cu" signal "TOP")
		(4 "In1.Cu" signal "L2GND")
		(6 "In2.Cu" signal "L3")
		(8 "In3.Cu" signal "L4VCC")
		(10 "In4.Cu" signal "L5VCC")
		(12 "In5.Cu" signal "L6")
		(14 "In6.Cu" signal "L7GND")
		(2 "B.Cu" signal "BOTTOM")
		(9 "F.Adhes" user "F.Adhesive")
		(11 "B.Adhes" user "B.Adhesive")
		(13 "F.Paste" user "Package Geometry/Pastemask Top")
		(15 "B.Paste" user "Package Geometry/Pastemask Bottom")
		(5 "F.SilkS" user "Ref Des/Silkscreen Top")
		(7 "B.SilkS" user "Ref Des/Silkscreen Bottom")
		(1 "F.Mask" user "Board Geometry/Soldermask Top")
		(3 "B.Mask" user "Board Geometry/Soldermask Bottom")
		(17 "Dwgs.User" user "User.Drawings")
		(19 "Cmts.User" user "User.Comments")
		(21 "Eco1.User" user "User.Eco1")
		(23 "Eco2.User" user "User.Eco2")
		(25 "Edge.Cuts" user "Board Geometry/Outline")
		(27 "Margin" user)
		(31 "F.CrtYd" user "Package Geometry/Place Bound Top")
		(29 "B.CrtYd" user "Package Geometry/Place Bound Bottom")
		(35 "F.Fab" user "Ref Des/Assembly Top")
		(33 "B.Fab" user "Ref Des/Assembly Bottom")
	)
	(footprint ""
		(layer "B.Cu")
		(at 124.2822 -64.4906 -90)
		(property "Reference" "C304"
			(at 0 0 90)
			(layer "B.SilkS")
			(hide yes)
			(effects
				(font
					(size 1.27 1.27)
				)
				(justify mirror)
			)
		)
		(property "Value" "SCD1U6D3V1KX-GP"
			(at 2.8321 -1.7399 270)
			(unlocked yes)
			(layer "B.Fab")
			(hide yes)
			(effects
				(font
					(size 1.016 1.016)
					(thickness 0.1524)
				)
				(justify mirror)
			)
		)
		(property "Device Type" "C0201H13"
			(at 2.8321 -3.2639 270)
			(unlocked yes)
			(layer "B.Fab")
			(hide yes)
			(effects
				(font
					(size 1.016 1.016)
					(thickness 0.1524)
				)
				(justify mirror)
			)
		)
		(duplicate_pad_numbers_are_jumpers no)
		(fp_rect
			(start 0.2794 0.6477)
			(end -0.2794 -0.6477)
			(stroke
				(width 0)
				(type default)
			)
			(fill no)
			(layer "B.CrtYd")
		)
		(fp_rect
			(start 0.2794 0.6477)
			(end -0.2794 -0.6477)
			(stroke
				(width 0)
				(type default)
			)
			(fill no)
			(layer "B.Fab")
		)
		(pad "1" smd custom
			(at 0 -0.2794 90)
			(size 0.0762 0.0762)
			(layers "B.Cu" "B.Mask" "B.Paste")
			(net "GB_VDDA")
			(options
				(clearance outline)
				(anchor circle)
			)
			(primitives
				(gr_poly
					(pts
						(arc
							(start 0.1524 0.127)
							(mid 0.137521 0.162921)
							(end 0.1016 0.1778)
						)
						(arc
							(start -0.1016 0.1778)
							(mid -0.137521 0.162921)
							(end -0.1524 0.127)
						)
						(arc
							(start -0.1524 -0.127)
							(mid -0.137521 -0.162921)
							(end -0.1016 -0.1778)
						)
						(arc
							(start 0.1016 -0.1778)
							(mid 0.137521 -0.162921)
							(end 0.1524 -0.127)
						)
					)
					(width 0)
					(fill yes)
				)
			)
		)
		(pad "2" smd custom
			(at 0 0.2794 90)
			(size 0.0762 0.0762)
			(layers "B.Cu" "B.Mask" "B.Paste")
			(net "GND")
			(options
				(clearance outline)
				(anchor circle)
			)
			(primitives
				(gr_poly
					(pts
						(arc
							(start 0.1524 0.127)
							(mid 0.137521 0.162921)
							(end 0.1016 0.1778)
						)
						(arc
							(start -0.1016 0.1778)
							(mid -0.137521 0.162921)
							(end -0.1524 0.127)
						)
						(arc
							(start -0.1524 -0.127)
							(mid -0.137521 -0.162921)
							(end -0.1016 -0.1778)
						)
						(arc
							(start 0.1016 -0.1778)
							(mid 0.137521 -0.162921)
							(end 0.1524 -0.127)
						)
					)
					(width 0)
					(fill yes)
				)
			)
		)
	)
	(footprint ""
		(layer "B.Cu")
		(at 114.76736 -59.4487)
		(property "Reference" "C237"
			(at 0 0 0)
			(layer "B.SilkS")
			(hide yes)
			(effects
				(font
					(size 1.27 1.27)
				)
				(justify mirror)
			)
		)
		(property "Value" "SCD1U6D3V1KX-GP"
			(at 2.8321 -1.7399 0)
			(unlocked yes)
			(layer "B.Fab")
			(hide yes)
			(effects
				(font
					(size 1.016 1.016)
					(thickness 0.1524)
				)
				(justify mirror)
			)
		)
		(property "Device Type" "C0201H13"
			(at 2.8321 -3.2639 0)
			(unlocked yes)
			(layer "B.Fab")
			(hide yes)
			(effects
				(font
					(size 1.016 1.016)
					(thickness 0.1524)
				)
				(justify mirror)
			)
		)
		(duplicate_pad_numbers_are_jumpers no)
		(fp_rect
			(start 0.2794 0.6477)
			(end -0.2794 -0.6477)
			(stroke
				(width 0)
				(type default)
			)
			(fill no)
			(layer "B.CrtYd")
		)
		(fp_rect
			(start 0.2794 0.6477)
			(end -0.2794 -0.6477)
			(stroke
				(width 0)
				(type default)
			)
			(fill no)
			(layer "B.Fab")
		)
		(pad "1" smd custom
			(at 0 -0.2794 180)
			(size 0.0762 0.0762)
			(layers "B.Cu" "B.Mask" "B.Paste")
			(net "GB_VDDA")
			(options
				(clearance outline)
				(anchor circle)
			)
			(primitives
				(gr_poly
					(pts
						(arc
							(start 0.1524 0.127)
							(mid 0.137521 0.162921)
							(end 0.1016 0.1778)
						)
						(arc
							(start -0.1016 0.1778)
							(mid -0.137521 0.162921)
							(end -0.1524 0.127)
						)
						(arc
							(start -0.1524 -0.127)
							(mid -0.137521 -0.162921)
							(end -0.1016 -0.1778)
						)
						(arc
							(start 0.1016 -0.1778)
							(mid 0.137521 -0.162921)
							(end 0.1524 -0.127)
						)
					)
					(width 0)
					(fill yes)
				)
			)
		)
		(pad "2" smd custom
			(at 0 0.2794 180)
			(size 0.0762 0.0762)
			(layers "B.Cu" "B.Mask" "B.Paste")
			(net "GND")
			(options
				(clearance outline)
				(anchor circle)
			)
			(primitives
				(gr_poly
					(pts
						(arc
							(start 0.1524 0.127)
							(mid 0.137521 0.162921)
							(end 0.1016 0.1778)
						)
						(arc
							(start -0.1016 0.1778)
							(mid -0.137521 0.162921)
							(end -0.1524 0.127)
						)
						(arc
							(start -0.1524 -0.127)
							(mid -0.137521 -0.162921)
							(end -0.1016 -0.1778)
						)
						(arc
							(start 0.1016 -0.1778)
							(mid 0.137521 -0.162921)
							(end 0.1524 -0.127)
						)
					)
					(width 0)
					(fill yes)
				)
			)
		)
	)
	(footprint ""
		(layer "B.Cu")
		(at 182.626 -28.6258 90)
		(property "Reference" "TP57"
			(at 0 0 90)
			(layer "B.SilkS")
			(hide yes)
			(effects
				(font
					(size 1.27 1.27)
				)
				(justify mirror)
			)
		)
		(property "Value" "TPAD28-2-GP"
			(at 0.0127 -1.6637 90)
			(unlocked yes)
			(layer "B.Fab")
			(hide yes)
			(effects
				(font
					(size 1.016 1.016)
					(thickness 0.1524)
				)
				(justify mirror)
			)
		)
		(property "Device Type" "TPAD28"
			(at 0.0127 -3.1877 90)
			(unlocked yes)
			(layer "B.Fab")
			(hide yes)
			(effects
				(font
					(size 1.016 1.016)
					(thickness 0.1524)
				)
				(justify mirror)
			)
		)
		(duplicate_pad_numbers_are_jumpers no)
		(fp_poly
			(pts
				(arc
					(start 0 0.3556)
					(mid 0 -0.3556)
					(end 0 0.3556)
				)
			)
			(stroke
				(width 0)
				(type default)
			)
			(fill no)
			(layer "B.CrtYd")
		)
		(fp_poly
			(pts
				(arc
					(start 0 0.6096)
					(mid 0 -0.6096)
					(end 0 0.6096)
				)
			)
			(stroke
				(width 0)
				(type default)
			)
			(fill no)
			(layer "B.Fab")
		)
		(pad "1" smd circle
			(at 0 0 270)
			(size 0.7112 0.7112)
			(layers "B.Cu" "B.Mask" "B.Paste")
			(net "IOC_GPIO_5")
		)
	)
	(footprint ""
		(layer "B.Cu")
		(at 174.1932 -118.5418 90)
		(property "Reference" "C707"
			(at 0 0 90)
			(layer "B.SilkS")
			(hide yes)
			(effects
				(font
					(size 1.27 1.27)
				)
				(justify mirror)
			)
		)
		(property "Value" "SC10U6D3V5KX-4GP"
			(at 0.0762 -6.1214 90)
			(unlocked yes)
			(layer "B.Fab")
			(hide yes)
			(effects
				(font
					(size 1.016 1.016)
					(thickness 0.1524)
				)
				(justify mirror)
			)
		)
		(property "Device Type" "C805H58"
			(at 0.0762 -8.1534 90)
			(unlocked yes)
			(layer "B.Fab")
			(hide yes)
			(effects
				(font
					(size 1.016 1.016)
					(thickness 0.1524)
				)
				(justify mirror)
			)
		)
		(duplicate_pad_numbers_are_jumpers no)
		(fp_line
			(start -0.635 0)
			(end 0.635 0)
			(stroke
				(width 0.508)
				(type default)
			)
			(layer "B.SilkS")
		)
		(fp_rect
			(start 0.9652 1.778)
			(end -0.9652 -1.778)
			(stroke
				(width 0)
				(type default)
			)
			(fill no)
			(layer "B.CrtYd")
		)
		(fp_poly
			(pts
				(xy 0.9652 -1.778) (xy -0.9652 -1.778) (xy -0.9652 1.778) (xy 0.9652 1.778)
			)
			(stroke
				(width 0)
				(type default)
			)
			(fill no)
			(layer "B.Fab")
		)
		(pad "1" smd rect
			(at 0 -0.9652 270)
			(size 1.397 1.143)
			(layers "B.Cu" "B.Mask" "B.Paste")
			(net "P3V3")
		)
		(pad "2" smd rect
			(at 0 0.9652 270)
			(size 1.397 1.143)
			(layers "B.Cu" "B.Mask" "B.Paste")
			(net "GND")
		)
	)
	(footprint ""
		(layer "B.Cu")
		(at 186.446922 -47.556674 -90)
		(property "Reference" "TP106"
			(at 0 0 90)
			(layer "B.SilkS")
			(hide yes)
			(effects
				(font
					(size 1.27 1.27)
				)
				(justify mirror)
			)
		)
		(property "Value" "TPAD28-2-GP"
			(at 0.0127 -1.6637 270)
			(unlocked yes)
			(layer "B.Fab")
			(hide yes)
			(effects
				(font
					(size 1.016 1.016)
					(thickness 0.1524)
				)
				(justify mirror)
			)
		)
		(property "Device Type" "TPAD28"
			(at 0.0127 -3.1877 270)
			(unlocked yes)
			(layer "B.Fab")
			(hide yes)
			(effects
				(font
					(size 1.016 1.016)
					(thickness 0.1524)
				)
				(justify mirror)
			)
		)
		(duplicate_pad_numbers_are_jumpers no)
		(fp_poly
			(pts
				(arc
					(start 0 -0.3556)
					(mid 0 0.3556)
					(end 0 -0.3556)
				)
			)
			(stroke
				(width 0)
				(type default)
			)
			(fill no)
			(layer "B.CrtYd")
		)
		(fp_poly
			(pts
				(arc
					(start 0 -0.6096)
					(mid 0 0.6096)
					(end 0 -0.6096)
				)
			)
			(stroke
				(width 0)
				(type default)
			)
			(fill no)
			(layer "B.Fab")
		)
		(pad "1" smd circle
			(at 0 0 90)
			(size 0.7112 0.7112)
			(layers "B.Cu" "B.Mask" "B.Paste")
			(net "XM_ADDR_19")
		)
	)
	(footprint ""
		(layer "B.Cu")
		(at 128.799844 -73.517252 -90)
		(property "Reference" "C308"
			(at 0 0 90)
			(layer "B.SilkS")
			(hide yes)
			(effects
				(font
					(size 1.27 1.27)
				)
				(justify mirror)
			)
		)
		(property "Value" "SCD1U6D3V1KX-GP"
			(at 2.8321 -1.7399 270)
			(unlocked yes)
			(layer "B.Fab")
			(hide yes)
			(effects
				(font
					(size 1.016 1.016)
					(thickness 0.1524)
				)
				(justify mirror)
			)
		)
		(property "Device Type" "C0201H13"
			(at 2.8321 -3.2639 270)
			(unlocked yes)
			(layer "B.Fab")
			(hide yes)
			(effects
				(font
					(size 1.016 1.016)
					(thickness 0.1524)
				)
				(justify mirror)
			)
		)
		(duplicate_pad_numbers_are_jumpers no)
		(fp_rect
			(start 0.2794 0.6477)
			(end -0.2794 -0.6477)
			(stroke
				(width 0)
				(type default)
			)
			(fill no)
			(layer "B.CrtYd")
		)
		(fp_rect
			(start 0.2794 0.6477)
			(end -0.2794 -0.6477)
			(stroke
				(width 0)
				(type default)
			)
			(fill no)
			(layer "B.Fab")
		)
		(pad "1" smd custom
			(at 0 -0.2794 90)
			(size 0.0762 0.0762)
			(layers "B.Cu" "B.Mask" "B.Paste")
			(net "GB_VDDA")
			(options
				(clearance outline)
				(anchor circle)
			)
			(primitives
				(gr_poly
					(pts
						(arc
							(start 0.1524 0.127)
							(mid 0.137521 0.162921)
							(end 0.1016 0.1778)
						)
						(arc
							(start -0.1016 0.1778)
							(mid -0.137521 0.162921)
							(end -0.1524 0.127)
						)
						(arc
							(start -0.1524 -0.127)
							(mid -0.137521 -0.162921)
							(end -0.1016 -0.1778)
						)
						(arc
							(start 0.1016 -0.1778)
							(mid 0.137521 -0.162921)
							(end 0.1524 -0.127)
						)
					)
					(width 0)
					(fill yes)
				)
			)
		)
		(pad "2" smd custom
			(at 0 0.2794 90)
			(size 0.0762 0.0762)
			(layers "B.Cu" "B.Mask" "B.Paste")
			(net "GND")
			(options
				(clearance outline)
				(anchor circle)
			)
			(primitives
				(gr_poly
					(pts
						(arc
							(start 0.1524 0.127)
							(mid 0.137521 0.162921)
							(end 0.1016 0.1778)
						)
						(arc
							(start -0.1016 0.1778)
							(mid -0.137521 0.162921)
							(end -0.1524 0.127)
						)
						(arc
							(start -0.1524 -0.127)
							(mid -0.137521 -0.162921)
							(end -0.1016 -0.1778)
						)
						(arc
							(start 0.1016 -0.1778)
							(mid 0.137521 -0.162921)
							(end 0.1524 -0.127)
						)
					)
					(width 0)
					(fill yes)
				)
			)
		)
	)
	(footprint ""
		(layer "B.Cu")
		(at 164.852858 -48.381158)
		(property "Reference" "C456"
			(at 0 0 0)
			(layer "B.SilkS")
			(hide yes)
			(effects
				(font
					(size 1.27 1.27)
				)
				(justify mirror)
			)
		)
		(property "Value" "SCD1U6D3V1KX-GP"
			(at 2.8321 -1.7399 0)
			(unlocked yes)
			(layer "B.Fab")
			(hide yes)
			(effects
				(font
					(size 1.016 1.016)
					(thickness 0.1524)
				)
				(justify mirror)
			)
		)
		(property "Device Type" "C0201H13"
			(at 2.8321 -3.2639 0)
			(unlocked yes)
			(layer "B.Fab")
			(hide yes)
			(effects
				(font
					(size 1.016 1.016)
					(thickness 0.1524)
				)
				(justify mirror)
			)
		)
		(duplicate_pad_numbers_are_jumpers no)
		(fp_rect
			(start 0.2794 0.6477)
			(end -0.2794 -0.6477)
			(stroke
				(width 0)
				(type default)
			)
			(fill no)
			(layer "B.CrtYd")
		)
		(fp_rect
			(start 0.2794 0.6477)
			(end -0.2794 -0.6477)
			(stroke
				(width 0)
				(type default)
			)
			(fill no)
			(layer "B.Fab")
		)
		(pad "1" smd custom
			(at 0 -0.2794 180)
			(size 0.0762 0.0762)
			(layers "B.Cu" "B.Mask" "B.Paste")
			(net "P1V8_C")
			(options
				(clearance outline)
				(anchor circle)
			)
			(primitives
				(gr_poly
					(pts
						(arc
							(start 0.1524 0.127)
							(mid 0.137521 0.162921)
							(end 0.1016 0.1778)
						)
						(arc
							(start -0.1016 0.1778)
							(mid -0.137521 0.162921)
							(end -0.1524 0.127)
						)
						(arc
							(start -0.1524 -0.127)
							(mid -0.137521 -0.162921)
							(end -0.1016 -0.1778)
						)
						(arc
							(start 0.1016 -0.1778)
							(mid 0.137521 -0.162921)
							(end 0.1524 -0.127)
						)
					)
					(width 0)
					(fill yes)
				)
			)
		)
		(pad "2" smd custom
			(at 0 0.2794 180)
			(size 0.0762 0.0762)
			(layers "B.Cu" "B.Mask" "B.Paste")
			(net "GND")
			(options
				(clearance outline)
				(anchor circle)
			)
			(primitives
				(gr_poly
					(pts
						(arc
							(start 0.1524 0.127)
							(mid 0.137521 0.162921)
							(end 0.1016 0.1778)
						)
						(arc
							(start -0.1016 0.1778)
							(mid -0.137521 0.162921)
							(end -0.1524 0.127)
						)
						(arc
							(start -0.1524 -0.127)
							(mid -0.137521 -0.162921)
							(end -0.1016 -0.1778)
						)
						(arc
							(start 0.1016 -0.1778)
							(mid 0.137521 -0.162921)
							(end 0.1524 -0.127)
						)
					)
					(width 0)
					(fill yes)
				)
			)
		)
	)
	(footprint ""
		(layer "B.Cu")
		(at 103.6066 -63.7286 -90)
		(property "Reference" "C154"
			(at 0 0 90)
			(layer "B.SilkS")
			(hide yes)
			(effects
				(font
					(size 1.27 1.27)
				)
				(justify mirror)
			)
		)
		(property "Value" "SCD1U6D3V1KX-GP"
			(at 2.8321 -1.7399 270)
			(unlocked yes)
			(layer "B.Fab")
			(hide yes)
			(effects
				(font
					(size 1.016 1.016)
					(thickness 0.1524)
				)
				(justify mirror)
			)
		)
		(property "Device Type" "C0201H13"
			(at 2.8321 -3.2639 270)
			(unlocked yes)
			(layer "B.Fab")
			(hide yes)
			(effects
				(font
					(size 1.016 1.016)
					(thickness 0.1524)
				)
				(justify mirror)
			)
		)
		(duplicate_pad_numbers_are_jumpers no)
		(fp_rect
			(start 0.2794 0.6477)
			(end -0.2794 -0.6477)
			(stroke
				(width 0)
				(type default)
			)
			(fill no)
			(layer "B.CrtYd")
		)
		(fp_rect
			(start 0.2794 0.6477)
			(end -0.2794 -0.6477)
			(stroke
				(width 0)
				(type default)
			)
			(fill no)
			(layer "B.Fab")
		)
		(pad "1" smd custom
			(at 0 -0.2794 90)
			(size 0.0762 0.0762)
			(layers "B.Cu" "B.Mask" "B.Paste")
			(net "P1V8_E")
			(options
				(clearance outline)
				(anchor circle)
			)
			(primitives
				(gr_poly
					(pts
						(arc
							(start 0.1524 0.127)
							(mid 0.137521 0.162921)
							(end 0.1016 0.1778)
						)
						(arc
							(start -0.1016 0.1778)
							(mid -0.137521 0.162921)
							(end -0.1524 0.127)
						)
						(arc
							(start -0.1524 -0.127)
							(mid -0.137521 -0.162921)
							(end -0.1016 -0.1778)
						)
						(arc
							(start 0.1016 -0.1778)
							(mid 0.137521 -0.162921)
							(end 0.1524 -0.127)
						)
					)
					(width 0)
					(fill yes)
				)
			)
		)
		(pad "2" smd custom
			(at 0 0.2794 90)
			(size 0.0762 0.0762)
			(layers "B.Cu" "B.Mask" "B.Paste")
			(net "GND")
			(options
				(clearance outline)
				(anchor circle)
			)
			(primitives
				(gr_poly
					(pts
						(arc
							(start 0.1524 0.127)
							(mid 0.137521 0.162921)
							(end 0.1016 0.1778)
						)
						(arc
							(start -0.1016 0.1778)
							(mid -0.137521 0.162921)
							(end -0.1524 0.127)
						)
						(arc
							(start -0.1524 -0.127)
							(mid -0.137521 -0.162921)
							(end -0.1016 -0.1778)
						)
						(arc
							(start 0.1016 -0.1778)
							(mid 0.137521 -0.162921)
							(end 0.1524 -0.127)
						)
					)
					(width 0)
					(fill yes)
				)
			)
		)
	)
	(footprint ""
		(layer "B.Cu")
		(at 115.189 -71.882)
		(property "Reference" "C133"
			(at 0 0 0)
			(layer "B.SilkS")
			(hide yes)
			(effects
				(font
					(size 1.27 1.27)
				)
				(justify mirror)
			)
		)
		(property "Value" "SCD1U6D3V1KX-GP"
			(at 2.8321 -1.7399 0)
			(unlocked yes)
			(layer "B.Fab")
			(hide yes)
			(effects
				(font
					(size 1.016 1.016)
					(thickness 0.1524)
				)
				(justify mirror)
			)
		)
		(property "Device Type" "C0201H13"
			(at 2.8321 -3.2639 0)
			(unlocked yes)
			(layer "B.Fab")
			(hide yes)
			(effects
				(font
					(size 1.016 1.016)
					(thickness 0.1524)
				)
				(justify mirror)
			)
		)
		(duplicate_pad_numbers_are_jumpers no)
		(fp_rect
			(start 0.2794 0.6477)
			(end -0.2794 -0.6477)
			(stroke
				(width 0)
				(type default)
			)
			(fill no)
			(layer "B.CrtYd")
		)
		(fp_rect
			(start 0.2794 0.6477)
			(end -0.2794 -0.6477)
			(stroke
				(width 0)
				(type default)
			)
			(fill no)
			(layer "B.Fab")
		)
		(pad "1" smd custom
			(at 0 -0.2794 180)
			(size 0.0762 0.0762)
			(layers "B.Cu" "B.Mask" "B.Paste")
			(net "P1V8_E")
			(options
				(clearance outline)
				(anchor circle)
			)
			(primitives
				(gr_poly
					(pts
						(arc
							(start 0.1524 0.127)
							(mid 0.137521 0.162921)
							(end 0.1016 0.1778)
						)
						(arc
							(start -0.1016 0.1778)
							(mid -0.137521 0.162921)
							(end -0.1524 0.127)
						)
						(arc
							(start -0.1524 -0.127)
							(mid -0.137521 -0.162921)
							(end -0.1016 -0.1778)
						)
						(arc
							(start 0.1016 -0.1778)
							(mid 0.137521 -0.162921)
							(end 0.1524 -0.127)
						)
					)
					(width 0)
					(fill yes)
				)
			)
		)
		(pad "2" smd custom
			(at 0 0.2794 180)
			(size 0.0762 0.0762)
			(layers "B.Cu" "B.Mask" "B.Paste")
			(net "GND")
			(options
				(clearance outline)
				(anchor circle)
			)
			(primitives
				(gr_poly
					(pts
						(arc
							(start 0.1524 0.127)
							(mid 0.137521 0.162921)
							(end 0.1016 0.1778)
						)
						(arc
							(start -0.1016 0.1778)
							(mid -0.137521 0.162921)
							(end -0.1524 0.127)
						)
						(arc
							(start -0.1524 -0.127)
							(mid -0.137521 -0.162921)
							(end -0.1016 -0.1778)
						)
						(arc
							(start 0.1016 -0.1778)
							(mid 0.137521 -0.162921)
							(end 0.1524 -0.127)
						)
					)
					(width 0)
					(fill yes)
				)
			)
		)
	)
)
